# S9S_MB_2U (Grand Teton) — schematic netlist excerpt (pin names and nets, part order shuffled) for the footprints in the layout excerpt that follows; sources: Cadence DE-HDL packaged netlist, KiCad conversion of 03242023_DA0F0TMBIJ0_F0T_Motherboard_J_brd_V01_OCP.brd

R943  Q_RES  10K 1% CHIP  pkg 0402LF  page 115 : A = P3V3_AUX ; B = PWRGD_FAIL_CPU0_GH_R1
PC435  Q_CAP  22UF 4V 20% X6S  pkg C0805  page 294 : A = PVCCFA_EHV_CPU1 ; B = GND
R3905  Q_RES  49.9 1% CHIP  pkg 0402LF  page 112 : A = I3C_SPD_DDREFGH_CPU1_LVC1_SCL_6 ; B = I3C_SPD_DDREFGH_CPU1_LVC1_SCL

(kicad_pcb
	(version 20260206)
	(generator "pcbnew")
	(generator_version "10.0")
	(general
		(thickness 1.6)
		(legacy_teardrops no)
	)
	(paper "A4")
	(title_block
		(title "03242023_DA0F0TMBIJ0_F0T_Motherboard_J_brd_V01_OCP.brd")
		(comment 1 "Grand Teton / footprints 6022-6024 of 6105")
	)
	(layers
		(0 "F.Cu" signal "TOP")
		(4 "In1.Cu" signal "GND")
		(6 "In2.Cu" signal "IN1")
		(8 "In3.Cu" signal "GND1")
		(10 "In4.Cu" signal "IN2")
		(12 "In5.Cu" signal "GND2")
		(14 "In6.Cu" signal "IN3")
		(16 "In7.Cu" signal "GND3")
		(18 "In8.Cu" signal "VCC")
		(20 "In9.Cu" signal "VCC1")
		(22 "In10.Cu" signal "GND4")
		(24 "In11.Cu" signal "IN4")
		(26 "In12.Cu" signal "GND5")
		(28 "In13.Cu" signal "IN5")
		(30 "In14.Cu" signal "GND6")
		(32 "In15.Cu" signal "IN6")
		(34 "In16.Cu" signal "GND7")
		(2 "B.Cu" signal "BOTTOM")
		(9 "F.Adhes" user "F.Adhesive")
		(11 "B.Adhes" user "B.Adhesive")
		(13 "F.Paste" user "Package Geometry/Pastemask Top")
		(15 "B.Paste" user "Package Geometry/Pastemask Bottom")
		(5 "F.SilkS" user "Ref Des/Silkscreen Top")
		(7 "B.SilkS" user "Ref Des/Silkscreen Bottom")
		(1 "F.Mask" user "Board Geometry/Soldermask Top")
		(3 "B.Mask" user "Board Geometry/Soldermask Bottom")
		(17 "Dwgs.User" user "User.Drawings")
		(19 "Cmts.User" user "User.Comments")
		(21 "Eco1.User" user "User.Eco1")
		(23 "Eco2.User" user "User.Eco2")
		(25 "Edge.Cuts" user "Board Geometry/Outline")
		(27 "Margin" user)
		(31 "F.CrtYd" user "Package Geometry/Place Bound Top")
		(29 "B.CrtYd" user "Package Geometry/Place Bound Bottom")
		(35 "F.Fab" user "Ref Des/Assembly Top")
		(33 "B.Fab" user "Ref Des/Assembly Bottom")
	)
	(footprint ""
		(layer "B.Cu")
		(at 208.30794 -316.258448 90)
		(property "Reference" "R3905"
			(at 0 0 90)
			(layer "B.SilkS")
			(hide yes)
			(effects
				(font
					(size 1.27 1.27)
				)
				(justify mirror)
			)
		)
		(property "Value" ""
			(at 0 0 90)
			(layer "B.Fab")
			(effects
				(font
					(size 1.27 1.27)
				)
				(justify mirror)
			)
		)
		(duplicate_pad_numbers_are_jumpers no)
		(fp_line
			(start 0.7874 -0.4064)
			(end -0.7874 -0.4064)
			(stroke
				(width 0.1524)
				(type default)
			)
			(layer "B.SilkS")
		)
		(fp_line
			(start -0.7874 -0.4064)
			(end -0.7874 0.4064)
			(stroke
				(width 0.1524)
				(type default)
			)
			(layer "B.SilkS")
		)
		(fp_line
			(start 0.7874 0.4064)
			(end 0.7874 -0.4064)
			(stroke
				(width 0.1524)
				(type default)
			)
			(layer "B.SilkS")
		)
		(fp_line
			(start -0.7874 0.4064)
			(end 0.7874 0.4064)
			(stroke
				(width 0.1524)
				(type default)
			)
			(layer "B.SilkS")
		)
		(fp_line
			(start 0.67945 -0.305054)
			(end 0.12065 -0.305054)
			(stroke
				(width 0.1)
				(type default)
			)
			(layer "B.Fab")
		)
		(fp_line
			(start 0.12065 -0.305054)
			(end 0.12065 -0.2794)
			(stroke
				(width 0.1)
				(type default)
			)
			(layer "B.Fab")
		)
		(fp_line
			(start -0.12065 -0.3048)
			(end -0.67945 -0.3048)
			(stroke
				(width 0.1)
				(type default)
			)
			(layer "B.Fab")
		)
		(fp_line
			(start -0.67945 -0.3048)
			(end -0.67945 0.3048)
			(stroke
				(width 0.1)
				(type default)
			)
			(layer "B.Fab")
		)
		(fp_line
			(start 0.12065 -0.2794)
			(end -0.12065 -0.2794)
			(stroke
				(width 0.1)
				(type default)
			)
			(layer "B.Fab")
		)
		(fp_line
			(start -0.12065 -0.2794)
			(end -0.12065 -0.3048)
			(stroke
				(width 0.1)
				(type default)
			)
			(layer "B.Fab")
		)
		(fp_line
			(start 0.12065 0.2794)
			(end 0.12065 0.3048)
			(stroke
				(width 0.1)
				(type default)
			)
			(layer "B.Fab")
		)
		(fp_line
			(start -0.120396 0.2794)
			(end 0.12065 0.2794)
			(stroke
				(width 0.1)
				(type default)
			)
			(layer "B.Fab")
		)
		(fp_line
			(start 0.67945 0.3048)
			(end 0.67945 -0.305054)
			(stroke
				(width 0.1)
				(type default)
			)
			(layer "B.Fab")
		)
		(fp_line
			(start 0.12065 0.3048)
			(end 0.67945 0.3048)
			(stroke
				(width 0.1)
				(type default)
			)
			(layer "B.Fab")
		)
		(fp_line
			(start -0.120396 0.3048)
			(end -0.120396 0.2794)
			(stroke
				(width 0.1)
				(type default)
			)
			(layer "B.Fab")
		)
		(fp_line
			(start -0.67945 0.3048)
			(end -0.120396 0.3048)
			(stroke
				(width 0.1)
				(type default)
			)
			(layer "B.Fab")
		)
		(pad "1" smd circle
			(at 0.40005 0 270)
			(size 0 0)
			(layers "B.Cu" "B.Mask" "B.Paste")
			(net "I3C_SPD_DDREFGH_CPU1_LVC1_SCL_6")
		)
		(pad "2" smd circle
			(at -0.40005 0 270)
			(size 0 0)
			(layers "B.Cu" "B.Mask" "B.Paste")
			(net "I3C_SPD_DDREFGH_CPU1_LVC1_SCL")
		)
	)
	(footprint ""
		(layer "B.Cu")
		(at 61.462412 -177.636678)
		(property "Reference" "PC435"
			(at 0 0 0)
			(layer "B.SilkS")
			(hide yes)
			(effects
				(font
					(size 1.27 1.27)
				)
				(justify mirror)
			)
		)
		(property "Value" ""
			(at 0 0 0)
			(layer "B.Fab")
			(effects
				(font
					(size 1.27 1.27)
				)
				(justify mirror)
			)
		)
		(duplicate_pad_numbers_are_jumpers no)
		(fp_line
			(start -1.524 -0.762)
			(end -1.524 0.762)
			(stroke
				(width 0.1524)
				(type default)
			)
			(layer "B.SilkS")
		)
		(fp_line
			(start -1.524 0.762)
			(end 1.524 0.762)
			(stroke
				(width 0.1524)
				(type default)
			)
			(layer "B.SilkS")
		)
		(fp_line
			(start 1.524 -0.762)
			(end -1.524 -0.762)
			(stroke
				(width 0.1524)
				(type default)
			)
			(layer "B.SilkS")
		)
		(fp_line
			(start 1.524 0.762)
			(end 1.524 -0.762)
			(stroke
				(width 0.1524)
				(type default)
			)
			(layer "B.SilkS")
		)
		(fp_line
			(start -1.1049 -0.724916)
			(end 1.1049 -0.724916)
			(stroke
				(width 0.1)
				(type default)
			)
			(layer "B.Fab")
		)
		(fp_line
			(start -1.1049 0.724916)
			(end -1.1049 -0.724916)
			(stroke
				(width 0.1)
				(type default)
			)
			(layer "B.Fab")
		)
		(fp_line
			(start 1.1049 -0.724916)
			(end 1.1049 0.724916)
			(stroke
				(width 0.1)
				(type default)
			)
			(layer "B.Fab")
		)
		(fp_line
			(start 1.1049 0.724916)
			(end -1.1049 0.724916)
			(stroke
				(width 0.1)
				(type default)
			)
			(layer "B.Fab")
		)
		(pad "1" smd rect
			(at 0.889 0)
			(size 1.016 1.27)
			(layers "B.Cu" "B.Mask" "B.Paste")
			(net "PVCCFA_EHV_CPU1")
		)
		(pad "2" smd rect
			(at -0.889 0)
			(size 1.016 1.27)
			(layers "B.Cu" "B.Mask" "B.Paste")
			(net "GND")
		)
	)
	(footprint ""
		(layer "B.Cu")
		(at 456.543918 -316.58306 90)
		(property "Reference" "R943"
			(at 0 0 90)
			(layer "B.SilkS")
			(hide yes)
			(effects
				(font
					(size 1.27 1.27)
				)
				(justify mirror)
			)
		)
		(property "Value" ""
			(at 0 0 90)
			(layer "B.Fab")
			(effects
				(font
					(size 1.27 1.27)
				)
				(justify mirror)
			)
		)
		(duplicate_pad_numbers_are_jumpers no)
		(fp_line
			(start 0.7874 -0.4064)
			(end -0.7874 -0.4064)
			(stroke
				(width 0.1524)
				(type default)
			)
			(layer "B.SilkS")
		)
		(fp_line
			(start -0.7874 -0.4064)
			(end -0.7874 0.4064)
			(stroke
				(width 0.1524)
				(type default)
			)
			(layer "B.SilkS")
		)
		(fp_line
			(start 0.7874 0.4064)
			(end 0.7874 -0.4064)
			(stroke
				(width 0.1524)
				(type default)
			)
			(layer "B.SilkS")
		)
		(fp_line
			(start -0.7874 0.4064)
			(end 0.7874 0.4064)
			(stroke
				(width 0.1524)
				(type default)
			)
			(layer "B.SilkS")
		)
		(fp_line
			(start 0.67945 -0.305054)
			(end 0.12065 -0.305054)
			(stroke
				(width 0.1)
				(type default)
			)
			(layer "B.Fab")
		)
		(fp_line
			(start 0.12065 -0.305054)
			(end 0.12065 -0.2794)
			(stroke
				(width 0.1)
				(type default)
			)
			(layer "B.Fab")
		)
		(fp_line
			(start -0.12065 -0.3048)
			(end -0.67945 -0.3048)
			(stroke
				(width 0.1)
				(type default)
			)
			(layer "B.Fab")
		)
		(fp_line
			(start -0.67945 -0.3048)
			(end -0.67945 0.3048)
			(stroke
				(width 0.1)
				(type default)
			)
			(layer "B.Fab")
		)
		(fp_line
			(start 0.12065 -0.2794)
			(end -0.12065 -0.2794)
			(stroke
				(width 0.1)
				(type default)
			)
			(layer "B.Fab")
		)
		(fp_line
			(start -0.12065 -0.2794)
			(end -0.12065 -0.3048)
			(stroke
				(width 0.1)
				(type default)
			)
			(layer "B.Fab")
		)
		(fp_line
			(start 0.12065 0.2794)
			(end 0.12065 0.3048)
			(stroke
				(width 0.1)
				(type default)
			)
			(layer "B.Fab")
		)
		(fp_line
			(start -0.120396 0.2794)
			(end 0.12065 0.2794)
			(stroke
				(width 0.1)
				(type default)
			)
			(layer "B.Fab")
		)
		(fp_line
			(start 0.67945 0.3048)
			(end 0.67945 -0.305054)
			(stroke
				(width 0.1)
				(type default)
			)
			(layer "B.Fab")
		)
		(fp_line
			(start 0.12065 0.3048)
			(end 0.67945 0.3048)
			(stroke
				(width 0.1)
				(type default)
			)
			(layer "B.Fab")
		)
		(fp_line
			(start -0.120396 0.3048)
			(end -0.120396 0.2794)
			(stroke
				(width 0.1)
				(type default)
			)
			(layer "B.Fab")
		)
		(fp_line
			(start -0.67945 0.3048)
			(end -0.120396 0.3048)
			(stroke
				(width 0.1)
				(type default)
			)
			(layer "B.Fab")
		)
		(pad "1" smd circle
			(at 0.40005 0 270)
			(size 0 0)
			(layers "B.Cu" "B.Mask" "B.Paste")
			(net "P3V3_AUX")
		)
		(pad "2" smd circle
			(at -0.40005 0 270)
			(size 0 0)
			(layers "B.Cu" "B.Mask" "B.Paste")
			(net "PWRGD_FAIL_CPU0_GH_R1")
		)
	)
)
